# S9S_MB_2U (Grand Teton) — schematic netlist excerpt (pin names and nets, part order shuffled) for the footprints in the layout excerpt that follows; sources: Cadence DE-HDL packaged netlist, KiCad conversion of 03242023_DA0F0TMBIJ0_F0T_Motherboard_J_brd_V01_OCP.brd

R2523  Q_RES  0 5% CHIP  pkg 0402LF  page 284 : A = IRQ_PVCCIN_CPU1_VRHOT_R_N ; B = IRQ_PVCCIN_CPU1_VRHOT_N
C1826  Q_CAP  0.1UF 25V 10% X7R  pkg 0402  page 160 : A = P3V3_AUX ; B = GND

(kicad_pcb
	(version 20260206)
	(generator "pcbnew")
	(generator_version "10.0")
	(general
		(thickness 1.6)
		(legacy_teardrops no)
	)
	(paper "A4")
	(title_block
		(title "03242023_DA0F0TMBIJ0_F0T_Motherboard_J_brd_V01_OCP.brd")
		(comment 1 "Grand Teton / footprints 4245-4247 of 6105")
	)
	(layers
		(0 "F.Cu" signal "TOP")
		(4 "In1.Cu" signal "GND")
		(6 "In2.Cu" signal "IN1")
		(8 "In3.Cu" signal "GND1")
		(10 "In4.Cu" signal "IN2")
		(12 "In5.Cu" signal "GND2")
		(14 "In6.Cu" signal "IN3")
		(16 "In7.Cu" signal "GND3")
		(18 "In8.Cu" signal "VCC")
		(20 "In9.Cu" signal "VCC1")
		(22 "In10.Cu" signal "GND4")
		(24 "In11.Cu" signal "IN4")
		(26 "In12.Cu" signal "GND5")
		(28 "In13.Cu" signal "IN5")
		(30 "In14.Cu" signal "GND6")
		(32 "In15.Cu" signal "IN6")
		(34 "In16.Cu" signal "GND7")
		(2 "B.Cu" signal "BOTTOM")
		(9 "F.Adhes" user "F.Adhesive")
		(11 "B.Adhes" user "B.Adhesive")
		(13 "F.Paste" user "Package Geometry/Pastemask Top")
		(15 "B.Paste" user "Package Geometry/Pastemask Bottom")
		(5 "F.SilkS" user "Ref Des/Silkscreen Top")
		(7 "B.SilkS" user "Ref Des/Silkscreen Bottom")
		(1 "F.Mask" user "Board Geometry/Soldermask Top")
		(3 "B.Mask" user "Board Geometry/Soldermask Bottom")
		(17 "Dwgs.User" user "User.Drawings")
		(19 "Cmts.User" user "User.Comments")
		(21 "Eco1.User" user "User.Eco1")
		(23 "Eco2.User" user "User.Eco2")
		(25 "Edge.Cuts" user "Board Geometry/Outline")
		(27 "Margin" user)
		(31 "F.CrtYd" user "Package Geometry/Place Bound Top")
		(29 "B.CrtYd" user "Package Geometry/Place Bound Bottom")
		(35 "F.Fab" user "Ref Des/Assembly Top")
		(33 "B.Fab" user "Ref Des/Assembly Bottom")
	)
	(footprint ""
		(layer "B.Cu")
		(at 103.25608 -359.070148 180)
		(property "Reference" "R2523"
			(at 0 0 0)
			(layer "B.SilkS")
			(hide yes)
			(effects
				(font
					(size 1.27 1.27)
				)
				(justify mirror)
			)
		)
		(property "Value" ""
			(at 0 0 0)
			(layer "B.Fab")
			(effects
				(font
					(size 1.27 1.27)
				)
				(justify mirror)
			)
		)
		(duplicate_pad_numbers_are_jumpers no)
		(fp_line
			(start 0.7874 0.4064)
			(end 0.7874 -0.4064)
			(stroke
				(width 0.1524)
				(type default)
			)
			(layer "B.SilkS")
		)
		(fp_line
			(start 0.7874 -0.4064)
			(end -0.7874 -0.4064)
			(stroke
				(width 0.1524)
				(type default)
			)
			(layer "B.SilkS")
		)
		(fp_line
			(start -0.7874 0.4064)
			(end 0.7874 0.4064)
			(stroke
				(width 0.1524)
				(type default)
			)
			(layer "B.SilkS")
		)
		(fp_line
			(start -0.7874 -0.4064)
			(end -0.7874 0.4064)
			(stroke
				(width 0.1524)
				(type default)
			)
			(layer "B.SilkS")
		)
		(fp_line
			(start 0.67945 0.3048)
			(end 0.67945 -0.305054)
			(stroke
				(width 0.1)
				(type default)
			)
			(layer "B.Fab")
		)
		(fp_line
			(start 0.67945 -0.305054)
			(end 0.12065 -0.305054)
			(stroke
				(width 0.1)
				(type default)
			)
			(layer "B.Fab")
		)
		(fp_line
			(start 0.12065 0.3048)
			(end 0.67945 0.3048)
			(stroke
				(width 0.1)
				(type default)
			)
			(layer "B.Fab")
		)
		(fp_line
			(start 0.12065 0.2794)
			(end 0.12065 0.3048)
			(stroke
				(width 0.1)
				(type default)
			)
			(layer "B.Fab")
		)
		(fp_line
			(start 0.12065 -0.2794)
			(end -0.12065 -0.2794)
			(stroke
				(width 0.1)
				(type default)
			)
			(layer "B.Fab")
		)
		(fp_line
			(start 0.12065 -0.305054)
			(end 0.12065 -0.2794)
			(stroke
				(width 0.1)
				(type default)
			)
			(layer "B.Fab")
		)
		(fp_line
			(start -0.120396 0.3048)
			(end -0.120396 0.2794)
			(stroke
				(width 0.1)
				(type default)
			)
			(layer "B.Fab")
		)
		(fp_line
			(start -0.120396 0.2794)
			(end 0.12065 0.2794)
			(stroke
				(width 0.1)
				(type default)
			)
			(layer "B.Fab")
		)
		(fp_line
			(start -0.12065 -0.2794)
			(end -0.12065 -0.3048)
			(stroke
				(width 0.1)
				(type default)
			)
			(layer "B.Fab")
		)
		(fp_line
			(start -0.12065 -0.3048)
			(end -0.67945 -0.3048)
			(stroke
				(width 0.1)
				(type default)
			)
			(layer "B.Fab")
		)
		(fp_line
			(start -0.67945 0.3048)
			(end -0.120396 0.3048)
			(stroke
				(width 0.1)
				(type default)
			)
			(layer "B.Fab")
		)
		(fp_line
			(start -0.67945 -0.3048)
			(end -0.67945 0.3048)
			(stroke
				(width 0.1)
				(type default)
			)
			(layer "B.Fab")
		)
		(pad "1" smd circle
			(at 0.40005 0)
			(size 0 0)
			(layers "B.Cu" "B.Mask" "B.Paste")
			(net "IRQ_PVCCIN_CPU1_VRHOT_R_N")
		)
		(pad "2" smd circle
			(at -0.40005 0)
			(size 0 0)
			(layers "B.Cu" "B.Mask" "B.Paste")
			(net "IRQ_PVCCIN_CPU1_VRHOT_N")
		)
	)
	(footprint ""
		(layer "B.Cu")
		(at 203.877926 -79.444342)
		(property "Reference" "C1826"
			(at 0 0 0)
			(layer "B.SilkS")
			(hide yes)
			(effects
				(font
					(size 1.27 1.27)
				)
				(justify mirror)
			)
		)
		(property "Value" ""
			(at 0 0 0)
			(layer "B.Fab")
			(effects
				(font
					(size 1.27 1.27)
				)
				(justify mirror)
			)
		)
		(duplicate_pad_numbers_are_jumpers no)
		(fp_line
			(start -0.7874 -0.4064)
			(end -0.7874 0.4064)
			(stroke
				(width 0.1524)
				(type default)
			)
			(layer "B.SilkS")
		)
		(fp_line
			(start -0.7874 0.4064)
			(end 0.7874 0.4064)
			(stroke
				(width 0.1524)
				(type default)
			)
			(layer "B.SilkS")
		)
		(fp_line
			(start 0.7874 -0.4064)
			(end -0.7874 -0.4064)
			(stroke
				(width 0.1524)
				(type default)
			)
			(layer "B.SilkS")
		)
		(fp_line
			(start 0.7874 0.4064)
			(end 0.7874 -0.4064)
			(stroke
				(width 0.1524)
				(type default)
			)
			(layer "B.SilkS")
		)
		(fp_line
			(start -0.67945 -0.3048)
			(end -0.67945 0.3048)
			(stroke
				(width 0.1)
				(type default)
			)
			(layer "B.Fab")
		)
		(fp_line
			(start -0.67945 0.3048)
			(end -0.120396 0.3048)
			(stroke
				(width 0.1)
				(type default)
			)
			(layer "B.Fab")
		)
		(fp_line
			(start -0.12065 -0.3048)
			(end -0.67945 -0.3048)
			(stroke
				(width 0.1)
				(type default)
			)
			(layer "B.Fab")
		)
		(fp_line
			(start -0.12065 -0.2794)
			(end -0.12065 -0.3048)
			(stroke
				(width 0.1)
				(type default)
			)
			(layer "B.Fab")
		)
		(fp_line
			(start -0.120396 0.2794)
			(end 0.12065 0.2794)
			(stroke
				(width 0.1)
				(type default)
			)
			(layer "B.Fab")
		)
		(fp_line
			(start -0.120396 0.3048)
			(end -0.120396 0.2794)
			(stroke
				(width 0.1)
				(type default)
			)
			(layer "B.Fab")
		)
		(fp_line
			(start 0.12065 -0.305054)
			(end 0.12065 -0.2794)
			(stroke
				(width 0.1)
				(type default)
			)
			(layer "B.Fab")
		)
		(fp_line
			(start 0.12065 -0.2794)
			(end -0.12065 -0.2794)
			(stroke
				(width 0.1)
				(type default)
			)
			(layer "B.Fab")
		)
		(fp_line
			(start 0.12065 0.2794)
			(end 0.12065 0.3048)
			(stroke
				(width 0.1)
				(type default)
			)
			(layer "B.Fab")
		)
		(fp_line
			(start 0.12065 0.3048)
			(end 0.67945 0.3048)
			(stroke
				(width 0.1)
				(type default)
			)
			(layer "B.Fab")
		)
		(fp_line
			(start 0.67945 -0.305054)
			(end 0.12065 -0.305054)
			(stroke
				(width 0.1)
				(type default)
			)
			(layer "B.Fab")
		)
		(fp_line
			(start 0.67945 0.3048)
			(end 0.67945 -0.305054)
			(stroke
				(width 0.1)
				(type default)
			)
			(layer "B.Fab")
		)
		(pad "1" smd circle
			(at 0.40005 0 180)
			(size 0 0)
			(layers "B.Cu" "B.Mask" "B.Paste")
			(net "P3V3_AUX")
		)
		(pad "2" smd circle
			(at -0.40005 0 180)
			(size 0 0)
			(layers "B.Cu" "B.Mask" "B.Paste")
			(net "GND")
		)
	)
	(footprint ""
		(layer "B.Cu")
		(at 11.80592 -400.030188)
		(property "Reference" ""
			(at 0 0 0)
			(layer "B.SilkS")
			(hide yes)
			(effects
				(font
					(size 1.27 1.27)
				)
				(justify mirror)
			)
		)
		(property "Value" ""
			(at 0 0 0)
			(layer "B.Fab")
			(effects
				(font
					(size 1.27 1.27)
				)
				(justify mirror)
			)
		)
		(duplicate_pad_numbers_are_jumpers no)
		(pad "1" smd circle
			(at 0 0 180)
			(size 0.9906 0.9906)
			(layers "B.Cu" "B.Mask" "B.Paste")
			(net "Net_288")
		)
		(zone
			(layer "B.Cu")
			(hatch none 0.5)
			(connect_pads
				(clearance 0)
			)
			(min_thickness 0.25)
			(keepout
				(tracks not_allowed)
				(vias allowed)
				(pads allowed)
				(copperpour not_allowed)
				(footprints allowed)
			)
			(placement
				(enabled no)
				(sheetname "")
			)
			(fill
				(thermal_gap 0.5)
				(thermal_bridge_width 0.5)
				(island_removal_mode 0)
			)
			(polygon
				(pts
					(arc
						(start 13.43152 -400.030188)
						(mid 10.18032 -400.030188)
						(end 13.43152 -400.030188)
					)
				)
			)
		)
	)
)
